(kicad_pcb
	(version 20241229)
	(generator "pcbnew")
	(generator_version "9.0")
	(general
		(thickness 1.599998)
		(legacy_teardrops no)
	)
	(paper "A4")
	(title_block
		(title "Artix - Datacenter Secure Control Module (DC-SCM)")
		(date "2024-11-06")
		(rev "1.1.3")
		(comment 9 "footprints 299-303 of 544")
	)
	(layers
		(0 "F.Cu" signal)
		(4 "In1.Cu" signal)
		(6 "In2.Cu" signal)
		(8 "In3.Cu" signal)
		(10 "In4.Cu" signal)
		(12 "In5.Cu" signal)
		(14 "In6.Cu" signal)
		(2 "B.Cu" signal)
		(9 "F.Adhes" user "F.Adhesive")
		(11 "B.Adhes" user "B.Adhesive")
		(13 "F.Paste" user)
		(15 "B.Paste" user)
		(5 "F.SilkS" user "F.Silkscreen")
		(7 "B.SilkS" user "B.Silkscreen")
		(1 "F.Mask" user)
		(3 "B.Mask" user)
		(17 "Dwgs.User" user "User.Drawings")
		(19 "Cmts.User" user "User.Comments")
		(21 "Eco1.User" user "User.Eco1")
		(23 "Eco2.User" user "User.Eco2")
		(25 "Edge.Cuts" user)
		(27 "Margin" user)
		(31 "F.CrtYd" user "F.Courtyard")
		(29 "B.CrtYd" user "B.Courtyard")
		(35 "F.Fab" user)
		(33 "B.Fab" user)
	)
	(footprint "antmicro-footprints:C_0201"
		(layer "B.Cu")
		(at 103.325 124.675)
		(descr "Capacitor SMD 0201")
		(tags "capacitor SMD 0201")
		(property "Reference" "C163"
			(at -1.325 1.225 0)
			(layer "B.SilkS")
			(effects
				(font
					(size 0.7 0.7)
					(thickness 0.15)
				)
				(justify right bottom mirror)
			)
		)
		(property "Value" "C_470n_0201"
			(at 0 -1.4 0)
			(layer "B.Fab")
			(effects
				(font
					(size 0.7 0.7)
					(thickness 0.15)
				)
				(justify right bottom mirror)
			)
		)
		(property "Datasheet" "https://product.tdk.com/en/search/capacitor/ceramic/mlcc/info?part_no=C0603X5R1A474M030BC"
			(at 0 0 0)
			(layer "F.Fab")
			(hide yes)
			(effects
				(font
					(size 1.27 1.27)
					(thickness 0.15)
				)
			)
		)
		(property "Description" "SMD Multilayer Ceramic Capacitor, 0.47 µF, 10 V, 0201 [0603 Metric], ± 20%, X5R, C"
			(at 0 0 0)
			(layer "F.Fab")
			(hide yes)
			(effects
				(font
					(size 1.27 1.27)
					(thickness 0.15)
				)
			)
		)
		(property "Author" "Antmicro"
			(at 0 0 0)
			(layer "B.Fab")
			(hide yes)
			(effects
				(font
					(size 1 1)
					(thickness 0.15)
				)
				(justify mirror)
			)
		)
		(property "Dielectric" ""
			(at 0 0 0)
			(layer "B.Fab")
			(hide yes)
			(effects
				(font
					(size 1 1)
					(thickness 0.15)
				)
				(justify mirror)
			)
		)
		(property "License" "Apache-2.0"
			(at 0 0 0)
			(layer "B.Fab")
			(hide yes)
			(effects
				(font
					(size 1 1)
					(thickness 0.15)
				)
				(justify mirror)
			)
		)
		(property "MPN" "C0603X5R1A474M030BC"
			(at 0 0 0)
			(layer "B.Fab")
			(hide yes)
			(effects
				(font
					(size 1 1)
					(thickness 0.15)
				)
				(justify mirror)
			)
		)
		(property "Manufacturer" "TDK"
			(at 0 0 0)
			(layer "B.Fab")
			(hide yes)
			(effects
				(font
					(size 1 1)
					(thickness 0.15)
				)
				(justify mirror)
			)
		)
		(property "Public" "False"
			(at 0 0 0)
			(layer "B.Fab")
			(hide yes)
			(effects
				(font
					(size 1 1)
					(thickness 0.15)
				)
				(justify mirror)
			)
		)
		(property "Val" "470n"
			(at 0 0 0)
			(layer "B.Fab")
			(hide yes)
			(effects
				(font
					(size 1 1)
					(thickness 0.15)
				)
				(justify mirror)
			)
		)
		(property "Voltage" ""
			(at 0 0 0)
			(layer "B.Fab")
			(hide yes)
			(effects
				(font
					(size 1 1)
					(thickness 0.15)
				)
				(justify mirror)
			)
		)
		(property "DNP" ""
			(at 0 0 0)
			(unlocked yes)
			(layer "B.Fab")
			(hide yes)
			(effects
				(font
					(size 1 1)
					(thickness 0.15)
				)
				(justify mirror)
			)
		)
		(sheetname "/FPGA power supply/")
		(sheetfile "fpga-power-supply.kicad_sch")
		(attr smd)
		(fp_rect
			(start -0.7 0.35)
			(end 0.7 -0.35)
			(stroke
				(width 0.05)
				(type default)
			)
			(fill no)
			(layer "B.CrtYd")
		)
		(fp_rect
			(start 0.3 -0.15)
			(end -0.301 0.149)
			(stroke
				(width 0.15)
				(type solid)
			)
			(fill no)
			(layer "B.Fab")
		)
		(pad "" smd roundrect
			(at -0.349 0.002)
			(size 0.318 0.36)
			(layers "B.Paste")
			(roundrect_rratio 0.25)
		)
		(pad "" smd roundrect
			(at 0.341 0.002)
			(size 0.318 0.36)
			(layers "B.Paste")
			(roundrect_rratio 0.25)
		)
		(pad "1" smd roundrect
			(at -0.321 0.002)
			(size 0.46 0.4)
			(layers "B.Cu" "B.Mask")
			(roundrect_rratio 0.25)
			(net 1 "GND")
			(pintype "passive")
		)
		(pad "2" smd roundrect
			(at 0.32 0.002)
			(size 0.46 0.4)
			(layers "B.Cu" "B.Mask")
			(roundrect_rratio 0.25)
			(net 6 "VCC1V0")
			(pintype "passive")
		)
	)
	(footprint "antmicro-footprints:C_0201"
		(layer "B.Cu")
		(at 101.325 123.625 180)
		(descr "Capacitor SMD 0201")
		(tags "capacitor SMD 0201")
		(property "Reference" "C175"
			(at -1.775 0.425 0)
			(layer "B.SilkS")
			(effects
				(font
					(size 0.7 0.7)
					(thickness 0.15)
				)
				(justify left bottom mirror)
			)
		)
		(property "Value" "C_470n_0201"
			(at 0 -1.4 0)
			(layer "B.Fab")
			(effects
				(font
					(size 0.7 0.7)
					(thickness 0.15)
				)
				(justify left bottom mirror)
			)
		)
		(property "Datasheet" "https://product.tdk.com/en/search/capacitor/ceramic/mlcc/info?part_no=C0603X5R1A474M030BC"
			(at 0 0 180)
			(layer "F.Fab")
			(hide yes)
			(effects
				(font
					(size 1.27 1.27)
					(thickness 0.15)
				)
			)
		)
		(property "Description" "SMD Multilayer Ceramic Capacitor, 0.47 µF, 10 V, 0201 [0603 Metric], ± 20%, X5R, C"
			(at 0 0 180)
			(layer "F.Fab")
			(hide yes)
			(effects
				(font
					(size 1.27 1.27)
					(thickness 0.15)
				)
			)
		)
		(property "Author" "Antmicro"
			(at 202.65 247.25 0)
			(layer "B.Fab")
			(hide yes)
			(effects
				(font
					(size 1 1)
					(thickness 0.15)
				)
				(justify mirror)
			)
		)
		(property "Dielectric" ""
			(at 202.65 247.25 0)
			(layer "B.Fab")
			(hide yes)
			(effects
				(font
					(size 1 1)
					(thickness 0.15)
				)
				(justify mirror)
			)
		)
		(property "License" "Apache-2.0"
			(at 202.65 247.25 0)
			(layer "B.Fab")
			(hide yes)
			(effects
				(font
					(size 1 1)
					(thickness 0.15)
				)
				(justify mirror)
			)
		)
		(property "MPN" "C0603X5R1A474M030BC"
			(at 202.65 247.25 0)
			(layer "B.Fab")
			(hide yes)
			(effects
				(font
					(size 1 1)
					(thickness 0.15)
				)
				(justify mirror)
			)
		)
		(property "Manufacturer" "TDK"
			(at 202.65 247.25 0)
			(layer "B.Fab")
			(hide yes)
			(effects
				(font
					(size 1 1)
					(thickness 0.15)
				)
				(justify mirror)
			)
		)
		(property "Public" "False"
			(at 202.65 247.25 0)
			(layer "B.Fab")
			(hide yes)
			(effects
				(font
					(size 1 1)
					(thickness 0.15)
				)
				(justify mirror)
			)
		)
		(property "Val" "470n"
			(at 202.65 247.25 0)
			(layer "B.Fab")
			(hide yes)
			(effects
				(font
					(size 1 1)
					(thickness 0.15)
				)
				(justify mirror)
			)
		)
		(property "Voltage" ""
			(at 202.65 247.25 0)
			(layer "B.Fab")
			(hide yes)
			(effects
				(font
					(size 1 1)
					(thickness 0.15)
				)
				(justify mirror)
			)
		)
		(property "DNP" ""
			(at 0 0 180)
			(unlocked yes)
			(layer "B.Fab")
			(hide yes)
			(effects
				(font
					(size 1 1)
					(thickness 0.15)
				)
				(justify mirror)
			)
		)
		(sheetname "/FPGA power supply/")
		(sheetfile "fpga-power-supply.kicad_sch")
		(attr smd)
		(fp_rect
			(start -0.7 0.35)
			(end 0.7 -0.35)
			(stroke
				(width 0.05)
				(type default)
			)
			(fill no)
			(layer "B.CrtYd")
		)
		(fp_rect
			(start 0.3 -0.15)
			(end -0.301 0.149)
			(stroke
				(width 0.15)
				(type solid)
			)
			(fill no)
			(layer "B.Fab")
		)
		(pad "" smd roundrect
			(at -0.349 0.002 180)
			(size 0.318 0.36)
			(layers "B.Paste")
			(roundrect_rratio 0.25)
		)
		(pad "" smd roundrect
			(at 0.341 0.002 180)
			(size 0.318 0.36)
			(layers "B.Paste")
			(roundrect_rratio 0.25)
		)
		(pad "1" smd roundrect
			(at -0.321 0.002 180)
			(size 0.46 0.4)
			(layers "B.Cu" "B.Mask")
			(roundrect_rratio 0.25)
			(net 1 "GND")
			(pintype "passive")
		)
		(pad "2" smd roundrect
			(at 0.32 0.002 180)
			(size 0.46 0.4)
			(layers "B.Cu" "B.Mask")
			(roundrect_rratio 0.25)
			(net 6 "VCC1V0")
			(pintype "passive")
		)
	)
	(footprint "antmicro-footprints:C_0402_1005Metric"
		(layer "B.Cu")
		(at 96.375 124.075 180)
		(descr "Capacitor SMD 0402")
		(tags "capacitor SMD 0402")
		(property "Reference" "C140"
			(at 20.475 -0.825 0)
			(layer "B.SilkS")
			(effects
				(font
					(size 0.7 0.7)
					(thickness 0.15)
				)
				(justify left bottom mirror)
			)
		)
		(property "Value" "C_470n_0402"
			(at 0 -1.4 0)
			(layer "B.Fab")
			(effects
				(font
					(size 0.7 0.7)
					(thickness 0.15)
				)
				(justify left bottom mirror)
			)
		)
		(property "Datasheet" "https://product.tdk.com/en/search/capacitor/ceramic/mlcc/info?part_no=C1005X5R1E474M050BB"
			(at 0 0 180)
			(layer "F.Fab")
			(hide yes)
			(effects
				(font
					(size 1.27 1.27)
					(thickness 0.15)
				)
			)
		)
		(property "Description" "SMD Multilayer Ceramic Capacitor, 0.47 µF, 25 V, 0402 [1005 Metric], ± 20%, X5R, C"
			(at 0 0 180)
			(layer "F.Fab")
			(hide yes)
			(effects
				(font
					(size 1.27 1.27)
					(thickness 0.15)
				)
			)
		)
		(property "Author" "Antmicro"
			(at 192.75 248.15 0)
			(layer "B.Fab")
			(hide yes)
			(effects
				(font
					(size 1 1)
					(thickness 0.15)
				)
				(justify mirror)
			)
		)
		(property "Dielectric" ""
			(at 192.75 248.15 0)
			(layer "B.Fab")
			(hide yes)
			(effects
				(font
					(size 1 1)
					(thickness 0.15)
				)
				(justify mirror)
			)
		)
		(property "License" "Apache-2.0"
			(at 192.75 248.15 0)
			(layer "B.Fab")
			(hide yes)
			(effects
				(font
					(size 1 1)
					(thickness 0.15)
				)
				(justify mirror)
			)
		)
		(property "MPN" "C1005X5R1E474M050BB"
			(at 192.75 248.15 0)
			(layer "B.Fab")
			(hide yes)
			(effects
				(font
					(size 1 1)
					(thickness 0.15)
				)
				(justify mirror)
			)
		)
		(property "Manufacturer" "TDK"
			(at 192.75 248.15 0)
			(layer "B.Fab")
			(hide yes)
			(effects
				(font
					(size 1 1)
					(thickness 0.15)
				)
				(justify mirror)
			)
		)
		(property "Val" "470n"
			(at 192.75 248.15 0)
			(layer "B.Fab")
			(hide yes)
			(effects
				(font
					(size 1 1)
					(thickness 0.15)
				)
				(justify mirror)
			)
		)
		(property "Voltage" ""
			(at 192.75 248.15 0)
			(layer "B.Fab")
			(hide yes)
			(effects
				(font
					(size 1 1)
					(thickness 0.15)
				)
				(justify mirror)
			)
		)
		(property "DNP" ""
			(at 0 0 180)
			(unlocked yes)
			(layer "B.Fab")
			(hide yes)
			(effects
				(font
					(size 1 1)
					(thickness 0.15)
				)
				(justify mirror)
			)
		)
		(sheetname "/FPGA power supply/")
		(sheetfile "fpga-power-supply.kicad_sch")
		(attr smd)
		(fp_rect
			(start -0.925 0.47)
			(end 0.925 -0.47)
			(stroke
				(width 0.05)
				(type default)
			)
			(fill no)
			(layer "B.CrtYd")
		)
		(fp_line
			(start 0.504 0.25)
			(end 0.504 -0.248)
			(stroke
				(width 0.15)
				(type solid)
			)
			(layer "B.Fab")
		)
		(fp_line
			(start 0.504 -0.248)
			(end -0.494 -0.248)
			(stroke
				(width 0.15)
				(type solid)
			)
			(layer "B.Fab")
		)
		(fp_line
			(start -0.494 0.25)
			(end 0.504 0.25)
			(stroke
				(width 0.15)
				(type solid)
			)
			(layer "B.Fab")
		)
		(fp_line
			(start -0.494 -0.248)
			(end -0.494 0.25)
			(stroke
				(width 0.15)
				(type solid)
			)
			(layer "B.Fab")
		)
		(pad "1" smd roundrect
			(at -0.48 0 180)
			(size 0.59 0.64)
			(layers "B.Cu" "B.Mask" "B.Paste")
			(roundrect_rratio 0.25)
			(net 1 "GND")
			(pintype "passive")
		)
		(pad "2" smd roundrect
			(at 0.48 0 180)
			(size 0.59 0.64)
			(layers "B.Cu" "B.Mask" "B.Paste")
			(roundrect_rratio 0.25)
			(net 6 "VCC1V0")
			(pintype "passive")
		)
	)
	(footprint "antmicro-footprints:C_0201"
		(layer "B.Cu")
		(at 96.725 123.175 180)
		(descr "Capacitor SMD 0201")
		(tags "capacitor SMD 0201")
		(property "Reference" "C142"
			(at 20.825 -0.625 0)
			(layer "B.SilkS")
			(effects
				(font
					(size 0.7 0.7)
					(thickness 0.15)
				)
				(justify left bottom mirror)
			)
		)
		(property "Value" "C_470n_0201"
			(at 0 -1.4 0)
			(layer "B.Fab")
			(effects
				(font
					(size 0.7 0.7)
					(thickness 0.15)
				)
				(justify left bottom mirror)
			)
		)
		(property "Datasheet" "https://product.tdk.com/en/search/capacitor/ceramic/mlcc/info?part_no=C0603X5R1A474M030BC"
			(at 0 0 180)
			(layer "F.Fab")
			(hide yes)
			(effects
				(font
					(size 1.27 1.27)
					(thickness 0.15)
				)
			)
		)
		(property "Description" "SMD Multilayer Ceramic Capacitor, 0.47 µF, 10 V, 0201 [0603 Metric], ± 20%, X5R, C"
			(at 0 0 180)
			(layer "F.Fab")
			(hide yes)
			(effects
				(font
					(size 1.27 1.27)
					(thickness 0.15)
				)
			)
		)
		(property "Author" "Antmicro"
			(at 193.45 246.35 0)
			(layer "B.Fab")
			(hide yes)
			(effects
				(font
					(size 1 1)
					(thickness 0.15)
				)
				(justify mirror)
			)
		)
		(property "Dielectric" ""
			(at 193.45 246.35 0)
			(layer "B.Fab")
			(hide yes)
			(effects
				(font
					(size 1 1)
					(thickness 0.15)
				)
				(justify mirror)
			)
		)
		(property "License" "Apache-2.0"
			(at 193.45 246.35 0)
			(layer "B.Fab")
			(hide yes)
			(effects
				(font
					(size 1 1)
					(thickness 0.15)
				)
				(justify mirror)
			)
		)
		(property "MPN" "C0603X5R1A474M030BC"
			(at 193.45 246.35 0)
			(layer "B.Fab")
			(hide yes)
			(effects
				(font
					(size 1 1)
					(thickness 0.15)
				)
				(justify mirror)
			)
		)
		(property "Manufacturer" "TDK"
			(at 193.45 246.35 0)
			(layer "B.Fab")
			(hide yes)
			(effects
				(font
					(size 1 1)
					(thickness 0.15)
				)
				(justify mirror)
			)
		)
		(property "Public" "False"
			(at 193.45 246.35 0)
			(layer "B.Fab")
			(hide yes)
			(effects
				(font
					(size 1 1)
					(thickness 0.15)
				)
				(justify mirror)
			)
		)
		(property "Val" "470n"
			(at 193.45 246.35 0)
			(layer "B.Fab")
			(hide yes)
			(effects
				(font
					(size 1 1)
					(thickness 0.15)
				)
				(justify mirror)
			)
		)
		(property "Voltage" ""
			(at 193.45 246.35 0)
			(layer "B.Fab")
			(hide yes)
			(effects
				(font
					(size 1 1)
					(thickness 0.15)
				)
				(justify mirror)
			)
		)
		(property "DNP" ""
			(at 0 0 180)
			(unlocked yes)
			(layer "B.Fab")
			(hide yes)
			(effects
				(font
					(size 1 1)
					(thickness 0.15)
				)
				(justify mirror)
			)
		)
		(sheetname "/FPGA power supply/")
		(sheetfile "fpga-power-supply.kicad_sch")
		(attr smd)
		(fp_rect
			(start -0.7 0.35)
			(end 0.7 -0.35)
			(stroke
				(width 0.05)
				(type default)
			)
			(fill no)
			(layer "B.CrtYd")
		)
		(fp_rect
			(start 0.3 -0.15)
			(end -0.301 0.149)
			(stroke
				(width 0.15)
				(type solid)
			)
			(fill no)
			(layer "B.Fab")
		)
		(pad "" smd roundrect
			(at -0.349 0.002 180)
			(size 0.318 0.36)
			(layers "B.Paste")
			(roundrect_rratio 0.25)
		)
		(pad "" smd roundrect
			(at 0.341 0.002 180)
			(size 0.318 0.36)
			(layers "B.Paste")
			(roundrect_rratio 0.25)
		)
		(pad "1" smd roundrect
			(at -0.321 0.002 180)
			(size 0.46 0.4)
			(layers "B.Cu" "B.Mask")
			(roundrect_rratio 0.25)
			(net 1 "GND")
			(pintype "passive")
		)
		(pad "2" smd roundrect
			(at 0.32 0.002 180)
			(size 0.46 0.4)
			(layers "B.Cu" "B.Mask")
			(roundrect_rratio 0.25)
			(net 6 "VCC1V0")
			(pintype "passive")
		)
	)
	(footprint "antmicro-footprints:C_0402_1005Metric"
		(layer "B.Cu")
		(at 102.275 118.375 -90)
		(descr "Capacitor SMD 0402")
		(tags "capacitor SMD 0402")
		(property "Reference" "C144"
			(at -1.575 0.475 90)
			(layer "B.SilkS")
			(effects
				(font
					(size 0.7 0.7)
					(thickness 0.15)
				)
				(justify left bottom mirror)
			)
		)
		(property "Value" "C_470n_0402"
			(at 0 -1.4 90)
			(layer "B.Fab")
			(effects
				(font
					(size 0.7 0.7)
					(thickness 0.15)
				)
				(justify left bottom mirror)
			)
		)
		(property "Datasheet" "https://product.tdk.com/en/search/capacitor/ceramic/mlcc/info?part_no=C1005X5R1E474M050BB"
			(at 0 0 270)
			(layer "F.Fab")
			(hide yes)
			(effects
				(font
					(size 1.27 1.27)
					(thickness 0.15)
				)
			)
		)
		(property "Description" "SMD Multilayer Ceramic Capacitor, 0.47 µF, 25 V, 0402 [1005 Metric], ± 20%, X5R, C"
			(at 0 0 270)
			(layer "F.Fab")
			(hide yes)
			(effects
				(font
					(size 1.27 1.27)
					(thickness 0.15)
				)
			)
		)
		(property "Author" "Antmicro"
			(at -16.1 220.65 0)
			(layer "B.Fab")
			(hide yes)
			(effects
				(font
					(size 1 1)
					(thickness 0.15)
				)
				(justify mirror)
			)
		)
		(property "Dielectric" ""
			(at -16.1 220.65 0)
			(layer "B.Fab")
			(hide yes)
			(effects
				(font
					(size 1 1)
					(thickness 0.15)
				)
				(justify mirror)
			)
		)
		(property "License" "Apache-2.0"
			(at -16.1 220.65 0)
			(layer "B.Fab")
			(hide yes)
			(effects
				(font
					(size 1 1)
					(thickness 0.15)
				)
				(justify mirror)
			)
		)
		(property "MPN" "C1005X5R1E474M050BB"
			(at -16.1 220.65 0)
			(layer "B.Fab")
			(hide yes)
			(effects
				(font
					(size 1 1)
					(thickness 0.15)
				)
				(justify mirror)
			)
		)
		(property "Manufacturer" "TDK"
			(at -16.1 220.65 0)
			(layer "B.Fab")
			(hide yes)
			(effects
				(font
					(size 1 1)
					(thickness 0.15)
				)
				(justify mirror)
			)
		)
		(property "Val" "470n"
			(at -16.1 220.65 0)
			(layer "B.Fab")
			(hide yes)
			(effects
				(font
					(size 1 1)
					(thickness 0.15)
				)
				(justify mirror)
			)
		)
		(property "Voltage" ""
			(at -16.1 220.65 0)
			(layer "B.Fab")
			(hide yes)
			(effects
				(font
					(size 1 1)
					(thickness 0.15)
				)
				(justify mirror)
			)
		)
		(sheetname "/FPGA power supply/")
		(sheetfile "fpga-power-supply.kicad_sch")
		(attr smd)
		(fp_rect
			(start -0.925 0.47)
			(end 0.925 -0.47)
			(stroke
				(width 0.05)
				(type default)
			)
			(fill no)
			(layer "B.CrtYd")
		)
		(fp_line
			(start -0.494 0.25)
			(end 0.504 0.25)
			(stroke
				(width 0.15)
				(type solid)
			)
			(layer "B.Fab")
		)
		(fp_line
			(start 0.504 0.25)
			(end 0.504 -0.248)
			(stroke
				(width 0.15)
				(type solid)
			)
			(layer "B.Fab")
		)
		(fp_line
			(start -0.494 -0.248)
			(end -0.494 0.25)
			(stroke
				(width 0.15)
				(type solid)
			)
			(layer "B.Fab")
		)
		(fp_line
			(start 0.504 -0.248)
			(end -0.494 -0.248)
			(stroke
				(width 0.15)
				(type solid)
			)
			(layer "B.Fab")
		)
		(pad "1" smd roundrect
			(at -0.48 0 270)
			(size 0.59 0.64)
			(layers "B.Cu" "B.Mask" "B.Paste")
			(roundrect_rratio 0.25)
			(net 1 "GND")
			(pintype "passive")
		)
		(pad "2" smd roundrect
			(at 0.48 0 270)
			(size 0.59 0.64)
			(layers "B.Cu" "B.Mask" "B.Paste")
			(roundrect_rratio 0.25)
			(net 5 "VCC1V8")
			(pintype "passive")
		)
	)
)
